# SCM (Grand Teton) — schematic netlist excerpt (pin names and nets, part order shuffled) for the footprints in the layout excerpt that follows; sources: Cadence DE-HDL packaged netlist, KiCad conversion of 12092022_DA0F0TMDCD0_F0T_Management_Board_D_brd_V3_OCP.brd

R275  Q_RES  0 5% CHIP  pkg 0402LF  page 54 : A = PWRGD_P1V8_AUX ; B = PWRGD_P1V8_AUX_R
R691  Q_RES  33.2 1% CHIP  pkg 0402LF  page 35 : A = RST_SGPIO_RESET_R_N ; B = RST_SGPIO_RESET_N

(kicad_pcb
	(version 20260206)
	(generator "pcbnew")
	(generator_version "10.0")
	(general
		(thickness 1.6)
		(legacy_teardrops no)
	)
	(paper "A4")
	(title_block
		(title "12092022_DA0F0TMDCD0_F0T_Management_Board_D_brd_V3_OCP.brd")
		(comment 1 "Grand Teton / footprints 282-283 of 1440")
	)
	(layers
		(0 "F.Cu" signal "TOP")
		(4 "In1.Cu" signal "GND")
		(6 "In2.Cu" signal "IN1")
		(8 "In3.Cu" signal "GND1")
		(10 "In4.Cu" signal "IN2")
		(12 "In5.Cu" signal "VCC")
		(14 "In6.Cu" signal "VCC1")
		(16 "In7.Cu" signal "IN3")
		(18 "In8.Cu" signal "GND2")
		(20 "In9.Cu" signal "IN4")
		(22 "In10.Cu" signal "GND3")
		(2 "B.Cu" signal "BOTTOM")
		(9 "F.Adhes" user "F.Adhesive")
		(11 "B.Adhes" user "B.Adhesive")
		(13 "F.Paste" user "Package Geometry/Pastemask Top")
		(15 "B.Paste" user "Package Geometry/Pastemask Bottom")
		(5 "F.SilkS" user "Ref Des/Silkscreen Top")
		(7 "B.SilkS" user "Ref Des/Silkscreen Bottom")
		(1 "F.Mask" user "Board Geometry/Soldermask Top")
		(3 "B.Mask" user "Board Geometry/Soldermask Bottom")
		(17 "Dwgs.User" user "User.Drawings")
		(19 "Cmts.User" user "User.Comments")
		(21 "Eco1.User" user "User.Eco1")
		(23 "Eco2.User" user "User.Eco2")
		(25 "Edge.Cuts" user "Board Geometry/Outline")
		(27 "Margin" user)
		(31 "F.CrtYd" user "Package Geometry/Place Bound Top")
		(29 "B.CrtYd" user "Package Geometry/Place Bound Bottom")
		(35 "F.Fab" user "Ref Des/Assembly Top")
		(33 "B.Fab" user "Ref Des/Assembly Bottom")
	)
	(footprint ""
		(layer "F.Cu")
		(at 38.989 -58.547 -90)
		(property "Reference" "R275"
			(at 0 0 270)
			(layer "F.SilkS")
			(hide yes)
			(effects
				(font
					(size 1.27 1.27)
				)
			)
		)
		(property "Value" ""
			(at 0 0 270)
			(layer "F.Fab")
			(effects
				(font
					(size 1.27 1.27)
				)
			)
		)
		(duplicate_pad_numbers_are_jumpers no)
		(fp_line
			(start -0.7874 0.4064)
			(end -0.7874 -0.4064)
			(stroke
				(width 0.1524)
				(type default)
			)
			(layer "F.SilkS")
		)
		(fp_line
			(start 0.7874 0.4064)
			(end -0.7874 0.4064)
			(stroke
				(width 0.1524)
				(type default)
			)
			(layer "F.SilkS")
		)
		(fp_line
			(start -0.7874 -0.4064)
			(end 0.7874 -0.4064)
			(stroke
				(width 0.1524)
				(type default)
			)
			(layer "F.SilkS")
		)
		(fp_line
			(start 0.7874 -0.4064)
			(end 0.7874 0.4064)
			(stroke
				(width 0.1524)
				(type default)
			)
			(layer "F.SilkS")
		)
		(fp_line
			(start -0.67945 0.3048)
			(end -0.67945 -0.305054)
			(stroke
				(width 0.1)
				(type default)
			)
			(layer "F.Fab")
		)
		(fp_line
			(start -0.12065 0.3048)
			(end -0.67945 0.3048)
			(stroke
				(width 0.1)
				(type default)
			)
			(layer "F.Fab")
		)
		(fp_line
			(start 0.120396 0.3048)
			(end 0.120396 0.2794)
			(stroke
				(width 0.1)
				(type default)
			)
			(layer "F.Fab")
		)
		(fp_line
			(start 0.67945 0.3048)
			(end 0.120396 0.3048)
			(stroke
				(width 0.1)
				(type default)
			)
			(layer "F.Fab")
		)
		(fp_line
			(start -0.12065 0.2794)
			(end -0.12065 0.3048)
			(stroke
				(width 0.1)
				(type default)
			)
			(layer "F.Fab")
		)
		(fp_line
			(start 0.120396 0.2794)
			(end -0.12065 0.2794)
			(stroke
				(width 0.1)
				(type default)
			)
			(layer "F.Fab")
		)
		(fp_line
			(start -0.12065 -0.2794)
			(end 0.12065 -0.2794)
			(stroke
				(width 0.1)
				(type default)
			)
			(layer "F.Fab")
		)
		(fp_line
			(start 0.12065 -0.2794)
			(end 0.12065 -0.3048)
			(stroke
				(width 0.1)
				(type default)
			)
			(layer "F.Fab")
		)
		(fp_line
			(start 0.12065 -0.3048)
			(end 0.67945 -0.3048)
			(stroke
				(width 0.1)
				(type default)
			)
			(layer "F.Fab")
		)
		(fp_line
			(start 0.67945 -0.3048)
			(end 0.67945 0.3048)
			(stroke
				(width 0.1)
				(type default)
			)
			(layer "F.Fab")
		)
		(fp_line
			(start -0.67945 -0.305054)
			(end -0.12065 -0.305054)
			(stroke
				(width 0.1)
				(type default)
			)
			(layer "F.Fab")
		)
		(fp_line
			(start -0.12065 -0.305054)
			(end -0.12065 -0.2794)
			(stroke
				(width 0.1)
				(type default)
			)
			(layer "F.Fab")
		)
		(pad "1" smd circle
			(at -0.40005 0 270)
			(size 0 0)
			(layers "F.Cu" "F.Mask" "F.Paste")
			(net "PWRGD_P1V8_AUX")
		)
		(pad "2" smd circle
			(at 0.40005 0 270)
			(size 0 0)
			(layers "F.Cu" "F.Mask" "F.Paste")
			(net "PWRGD_P1V8_AUX_R")
		)
	)
	(footprint ""
		(layer "F.Cu")
		(at 12.319 -87.376 180)
		(property "Reference" "R691"
			(at 0 0 180)
			(layer "F.SilkS")
			(hide yes)
			(effects
				(font
					(size 1.27 1.27)
				)
			)
		)
		(property "Value" ""
			(at 0 0 180)
			(layer "F.Fab")
			(effects
				(font
					(size 1.27 1.27)
				)
			)
		)
		(duplicate_pad_numbers_are_jumpers no)
		(fp_line
			(start 0.7874 0.4064)
			(end -0.7874 0.4064)
			(stroke
				(width 0.1524)
				(type default)
			)
			(layer "F.SilkS")
		)
		(fp_line
			(start 0.7874 -0.4064)
			(end 0.7874 0.4064)
			(stroke
				(width 0.1524)
				(type default)
			)
			(layer "F.SilkS")
		)
		(fp_line
			(start -0.7874 0.4064)
			(end -0.7874 -0.4064)
			(stroke
				(width 0.1524)
				(type default)
			)
			(layer "F.SilkS")
		)
		(fp_line
			(start -0.7874 -0.4064)
			(end 0.7874 -0.4064)
			(stroke
				(width 0.1524)
				(type default)
			)
			(layer "F.SilkS")
		)
		(fp_line
			(start 0.67945 0.3048)
			(end 0.120396 0.3048)
			(stroke
				(width 0.1)
				(type default)
			)
			(layer "F.Fab")
		)
		(fp_line
			(start 0.67945 -0.3048)
			(end 0.67945 0.3048)
			(stroke
				(width 0.1)
				(type default)
			)
			(layer "F.Fab")
		)
		(fp_line
			(start 0.12065 -0.2794)
			(end 0.12065 -0.3048)
			(stroke
				(width 0.1)
				(type default)
			)
			(layer "F.Fab")
		)
		(fp_line
			(start 0.12065 -0.3048)
			(end 0.67945 -0.3048)
			(stroke
				(width 0.1)
				(type default)
			)
			(layer "F.Fab")
		)
		(fp_line
			(start 0.120396 0.3048)
			(end 0.120396 0.2794)
			(stroke
				(width 0.1)
				(type default)
			)
			(layer "F.Fab")
		)
		(fp_line
			(start 0.120396 0.2794)
			(end -0.12065 0.2794)
			(stroke
				(width 0.1)
				(type default)
			)
			(layer "F.Fab")
		)
		(fp_line
			(start -0.12065 0.3048)
			(end -0.67945 0.3048)
			(stroke
				(width 0.1)
				(type default)
			)
			(layer "F.Fab")
		)
		(fp_line
			(start -0.12065 0.2794)
			(end -0.12065 0.3048)
			(stroke
				(width 0.1)
				(type default)
			)
			(layer "F.Fab")
		)
		(fp_line
			(start -0.12065 -0.2794)
			(end 0.12065 -0.2794)
			(stroke
				(width 0.1)
				(type default)
			)
			(layer "F.Fab")
		)
		(fp_line
			(start -0.12065 -0.305054)
			(end -0.12065 -0.2794)
			(stroke
				(width 0.1)
				(type default)
			)
			(layer "F.Fab")
		)
		(fp_line
			(start -0.67945 0.3048)
			(end -0.67945 -0.305054)
			(stroke
				(width 0.1)
				(type default)
			)
			(layer "F.Fab")
		)
		(fp_line
			(start -0.67945 -0.305054)
			(end -0.12065 -0.305054)
			(stroke
				(width 0.1)
				(type default)
			)
			(layer "F.Fab")
		)
		(pad "1" smd circle
			(at -0.40005 0 180)
			(size 0 0)
			(layers "F.Cu" "F.Mask" "F.Paste")
			(net "RST_SGPIO_RESET_R_N")
		)
		(pad "2" smd circle
			(at 0.40005 0 180)
			(size 0 0)
			(layers "F.Cu" "F.Mask" "F.Paste")
			(net "RST_SGPIO_RESET_N")
		)
	)
)
